(kicad_pcb
	(version 20241229)
	(generator "pcbnew")
	(generator_version "9.0")
	(general
		(thickness 1.61)
		(legacy_teardrops no)
	)
	(paper "A3")
	(title_block
		(title "RDIMM DDR5 Tester")
		(date "2026-05-21")
		(rev "2.2.0")
		(company "Antmicro")
		(comment 9 "footprints 322-327 of 796")
	)
	(layers
		(0 "F.Cu" signal)
		(4 "In1.Cu" power)
		(6 "In2.Cu" mixed)
		(8 "In3.Cu" power)
		(10 "In4.Cu" mixed)
		(12 "In5.Cu" power)
		(14 "In6.Cu" mixed)
		(16 "In7.Cu" power)
		(18 "In8.Cu" power)
		(20 "In9.Cu" mixed)
		(22 "In10.Cu" power)
		(2 "B.Cu" signal)
		(9 "F.Adhes" user "F.Adhesive")
		(11 "B.Adhes" user "B.Adhesive")
		(13 "F.Paste" user)
		(15 "B.Paste" user)
		(5 "F.SilkS" user "F.Silkscreen")
		(7 "B.SilkS" user "B.Silkscreen")
		(1 "F.Mask" user)
		(3 "B.Mask" user)
		(17 "Dwgs.User" user "User.Drawings")
		(19 "Cmts.User" user "User.Comments")
		(21 "Eco1.User" user "User.Eco1")
		(23 "Eco2.User" user "User.Eco2")
		(25 "Edge.Cuts" user)
		(27 "Margin" user)
		(31 "F.CrtYd" user "F.Courtyard")
		(29 "B.CrtYd" user "B.Courtyard")
		(35 "F.Fab" user)
		(33 "B.Fab" user)
	)
	(footprint "antmicro-footprints:SOT-143-4"
		(layer "F.Cu")
		(at 254.173999 136.2625 -90)
		(descr "http://datasheets.maximintegrated.com/en/ds/MAX6816-MAX6818.pdf")
		(property "Reference" "U26"
			(at -1.0725 -2.866001 90)
			(layer "F.SilkS")
			(effects
				(font
					(size 0.7 0.7)
					(thickness 0.15)
				)
				(justify right bottom)
			)
		)
		(property "Value" "MAX812REUS+T"
			(at 0 2.999 90)
			(layer "F.Fab")
			(effects
				(font
					(size 0.7 0.7)
					(thickness 0.15)
				)
				(justify right bottom)
			)
		)
		(property "Datasheet" "https://datasheets.maximintegrated.com/en/ds/MAX811-MAX812T.pdf"
			(at 0 0 270)
			(layer "F.Fab")
			(hide yes)
			(effects
				(font
					(size 1.27 1.27)
					(thickness 0.15)
				)
			)
		)
		(property "Manufacturer" "Maxim Integrated Products"
			(at 0 0 270)
			(unlocked yes)
			(layer "F.Fab")
			(hide yes)
			(effects
				(font
					(size 1 1)
					(thickness 0.15)
				)
			)
		)
		(property "MPN" "MAX812REUS+T"
			(at 0 0 270)
			(unlocked yes)
			(layer "F.Fab")
			(hide yes)
			(effects
				(font
					(size 1 1)
					(thickness 0.15)
				)
			)
		)
		(property "License" "Apache-2.0"
			(at 0 0 270)
			(unlocked yes)
			(layer "F.Fab")
			(hide yes)
			(effects
				(font
					(size 1 1)
					(thickness 0.15)
				)
			)
		)
		(property "Author" "Antmicro"
			(at 0 0 270)
			(unlocked yes)
			(layer "F.Fab")
			(hide yes)
			(effects
				(font
					(size 1 1)
					(thickness 0.15)
				)
			)
		)
		(sheetname "/Supply/")
		(sheetfile "supply.kicad_sch")
		(attr smd)
		(fp_circle
			(center -2.1 1.7)
			(end -2.05 1.7)
			(stroke
				(width 0.15)
				(type solid)
			)
			(fill yes)
			(layer "F.SilkS")
		)
		(fp_rect
			(start -1.776 -1.896)
			(end 1.773 1.895)
			(stroke
				(width 0.05)
				(type solid)
			)
			(fill no)
			(layer "F.CrtYd")
		)
		(fp_line
			(start -1.46 0.65)
			(end 1.459 0.65)
			(stroke
				(width 0.15)
				(type solid)
			)
			(layer "F.Fab")
		)
		(fp_line
			(start -1.46 0.65)
			(end -1.46 -0.652)
			(stroke
				(width 0.15)
				(type solid)
			)
			(layer "F.Fab")
		)
		(fp_line
			(start 1.459 -0.652)
			(end 1.459 0.65)
			(stroke
				(width 0.15)
				(type solid)
			)
			(layer "F.Fab")
		)
		(fp_line
			(start 1.459 -0.652)
			(end -1.46 -0.652)
			(stroke
				(width 0.15)
				(type solid)
			)
			(layer "F.Fab")
		)
		(fp_text user "License: Apache-2.0"
			(at -1.601 7.4 270)
			(layer "F.Fab")
			(effects
				(font
					(size 0.7 0.7)
					(thickness 0.15)
				)
				(justify left bottom)
			)
		)
		(fp_text user "${REFERENCE}"
			(at -1.601 4.998 270)
			(layer "F.Fab")
			(effects
				(font
					(size 0.7 0.7)
					(thickness 0.15)
				)
				(justify left bottom)
			)
		)
		(fp_text user "Author: Antmicro"
			(at -1.601 6.2 270)
			(layer "F.Fab")
			(effects
				(font
					(size 0.7 0.7)
					(thickness 0.15)
				)
				(justify left bottom)
			)
		)
		(pad "1" smd roundrect
			(at -0.76 0.998 270)
			(size 0.94 1.31)
			(layers "F.Cu" "F.Mask" "F.Paste")
			(roundrect_rratio 0.25)
			(net 1 "GND")
			(pinfunction "GND")
			(pintype "power_in")
		)
		(pad "2" smd roundrect
			(at 0.959 0.998 270)
			(size 0.55 1.31)
			(layers "F.Cu" "F.Mask" "F.Paste")
			(roundrect_rratio 0.25)
			(net 287 "Net-(Q17-G)")
			(pinfunction "~{RST}")
			(pintype "output")
		)
		(pad "3" smd roundrect
			(at 0.959 -1 270)
			(size 0.55 1.31)
			(layers "F.Cu" "F.Mask" "F.Paste")
			(roundrect_rratio 0.25)
			(net 286 "Net-(Q16-D)")
			(pinfunction "~{MR}")
			(pintype "input")
		)
		(pad "4" smd roundrect
			(at -0.96 -1 270)
			(size 0.55 1.31)
			(layers "F.Cu" "F.Mask" "F.Paste")
			(roundrect_rratio 0.25)
			(net 38 "+3V3_AON")
			(pinfunction "VCC")
			(pintype "power_in")
		)
	)
	(footprint "antmicro-footprints:R_0402_1005Metric"
		(layer "F.Cu")
		(at 125.681 168.3125 90)
		(descr "Resistor SMD 0402")
		(tags "resistor SMD 0402")
		(property "Reference" "R217"
			(at -3.825 0.619 90)
			(layer "F.SilkS")
			(effects
				(font
					(size 0.7 0.7)
					(thickness 0.15)
				)
				(justify left bottom)
			)
		)
		(property "Value" "R_64k9_0402"
			(at -1.011843 1.772047 90)
			(layer "F.Fab")
			(effects
				(font
					(size 0.7 0.7)
					(thickness 0.15)
				)
				(justify left bottom)
			)
		)
		(property "Datasheet" "https://www.bourns.com/docs/product-datasheets/cr.pdf"
			(at 0 0 90)
			(layer "F.Fab")
			(hide yes)
			(effects
				(font
					(size 1.27 1.27)
					(thickness 0.15)
				)
			)
		)
		(property "MPN" "CR0402-FX-6492GLF"
			(at 0 0 90)
			(unlocked yes)
			(layer "F.Fab")
			(hide yes)
			(effects
				(font
					(size 1 1)
					(thickness 0.15)
				)
			)
		)
		(property "Manufacturer" "Bourns"
			(at 0 0 90)
			(unlocked yes)
			(layer "F.Fab")
			(hide yes)
			(effects
				(font
					(size 1 1)
					(thickness 0.15)
				)
			)
		)
		(property "License" "Apache-2.0"
			(at 0 0 90)
			(unlocked yes)
			(layer "F.Fab")
			(hide yes)
			(effects
				(font
					(size 1 1)
					(thickness 0.15)
				)
			)
		)
		(property "Author" "Antmicro"
			(at 0 0 90)
			(unlocked yes)
			(layer "F.Fab")
			(hide yes)
			(effects
				(font
					(size 1 1)
					(thickness 0.15)
				)
			)
		)
		(property "Val" "64k9"
			(at 0 0 90)
			(unlocked yes)
			(layer "F.Fab")
			(hide yes)
			(effects
				(font
					(size 1 1)
					(thickness 0.15)
				)
			)
		)
		(property "Tolerance" "1%"
			(at 0 0 90)
			(unlocked yes)
			(layer "F.Fab")
			(hide yes)
			(effects
				(font
					(size 1 1)
					(thickness 0.15)
				)
			)
		)
		(sheetname "/HDMI + SD Card/")
		(sheetfile "hdmi-sd-card.kicad_sch")
		(attr smd exclude_from_bom dnp)
		(fp_rect
			(start -0.925 -0.47)
			(end 0.925 0.47)
			(stroke
				(width 0.05)
				(type default)
			)
			(fill no)
			(layer "F.CrtYd")
		)
		(fp_rect
			(start -0.5 -0.25)
			(end 0.5 0.25)
			(stroke
				(width 0.15)
				(type solid)
			)
			(fill no)
			(layer "F.Fab")
		)
		(fp_text user "Author: Antmicro"
			(at -0.95 4.169 90)
			(layer "F.Fab")
			(effects
				(font
					(size 0.7 0.7)
					(thickness 0.15)
				)
				(justify left bottom)
			)
		)
		(fp_text user "${REFERENCE}"
			(at -0.95 3.168 90)
			(layer "F.Fab")
			(effects
				(font
					(size 0.7 0.7)
					(thickness 0.15)
				)
				(justify left bottom)
			)
		)
		(fp_text user "License: Apache-2.0"
			(at -0.95 5.169 90)
			(layer "F.Fab")
			(effects
				(font
					(size 0.7 0.7)
					(thickness 0.15)
				)
				(justify left bottom)
			)
		)
		(pad "1" smd roundrect
			(at -0.48 0 90)
			(size 0.59 0.64)
			(layers "F.Cu" "F.Mask" "F.Paste")
			(roundrect_rratio 0.25)
			(net 1 "GND")
			(pintype "passive")
		)
		(pad "2" smd roundrect
			(at 0.48 0 90)
			(size 0.59 0.64)
			(layers "F.Cu" "F.Mask" "F.Paste")
			(roundrect_rratio 0.25)
			(net 736 "/HDMI + SD Card/PRE_SEL")
			(pintype "passive")
		)
	)
	(footprint "antmicro-footprints:R_0402_1005Metric"
		(layer "F.Cu")
		(at 121.05 112.736461 -90)
		(descr "Resistor SMD 0402")
		(tags "resistor SMD 0402")
		(property "Reference" "R11"
			(at -1.161461 -1.475 90)
			(layer "F.SilkS")
			(effects
				(font
					(size 0.7 0.7)
					(thickness 0.15)
				)
				(justify right bottom)
			)
		)
		(property "Value" "R_330R_0402"
			(at -1.011843 1.772047 90)
			(layer "F.Fab")
			(effects
				(font
					(size 0.7 0.7)
					(thickness 0.15)
				)
				(justify right bottom)
			)
		)
		(property "Datasheet" "https://www.bourns.com/docs/product-datasheets/cr.pdf"
			(at 0 0 270)
			(layer "F.Fab")
			(hide yes)
			(effects
				(font
					(size 1.27 1.27)
					(thickness 0.15)
				)
			)
		)
		(property "Manufacturer" "Bourns"
			(at 0 0 270)
			(unlocked yes)
			(layer "F.Fab")
			(hide yes)
			(effects
				(font
					(size 1 1)
					(thickness 0.15)
				)
			)
		)
		(property "MPN" "CR0402-FX-3300GLF"
			(at 0 0 270)
			(unlocked yes)
			(layer "F.Fab")
			(hide yes)
			(effects
				(font
					(size 1 1)
					(thickness 0.15)
				)
			)
		)
		(property "Val" "330R"
			(at 0 0 270)
			(unlocked yes)
			(layer "F.Fab")
			(hide yes)
			(effects
				(font
					(size 1 1)
					(thickness 0.15)
				)
			)
		)
		(property "License" "Apache-2.0"
			(at 0 0 270)
			(unlocked yes)
			(layer "F.Fab")
			(hide yes)
			(effects
				(font
					(size 1 1)
					(thickness 0.15)
				)
			)
		)
		(property "Author" "Antmicro"
			(at 0 0 270)
			(unlocked yes)
			(layer "F.Fab")
			(hide yes)
			(effects
				(font
					(size 1 1)
					(thickness 0.15)
				)
			)
		)
		(property "Tolerance" "1%"
			(at 0 0 270)
			(unlocked yes)
			(layer "F.Fab")
			(hide yes)
			(effects
				(font
					(size 1 1)
					(thickness 0.15)
				)
			)
		)
		(sheetname "/FPGA Config/")
		(sheetfile "fpga-config.kicad_sch")
		(attr smd)
		(fp_rect
			(start -0.925 -0.47)
			(end 0.925 0.47)
			(stroke
				(width 0.05)
				(type default)
			)
			(fill no)
			(layer "F.CrtYd")
		)
		(fp_rect
			(start -0.5 -0.25)
			(end 0.5 0.25)
			(stroke
				(width 0.15)
				(type solid)
			)
			(fill no)
			(layer "F.Fab")
		)
		(fp_text user "Author: Antmicro"
			(at -0.95 4.169 270)
			(layer "F.Fab")
			(effects
				(font
					(size 0.7 0.7)
					(thickness 0.15)
				)
				(justify left bottom)
			)
		)
		(fp_text user "${REFERENCE}"
			(at -0.95 3.168 270)
			(layer "F.Fab")
			(effects
				(font
					(size 0.7 0.7)
					(thickness 0.15)
				)
				(justify left bottom)
			)
		)
		(fp_text user "License: Apache-2.0"
			(at -0.95 5.169 270)
			(layer "F.Fab")
			(effects
				(font
					(size 0.7 0.7)
					(thickness 0.15)
				)
				(justify left bottom)
			)
		)
		(pad "1" smd roundrect
			(at -0.48 0 270)
			(size 0.59 0.64)
			(layers "F.Cu" "F.Mask" "F.Paste")
			(roundrect_rratio 0.25)
			(net 783 "Net-(D1-C)")
			(pintype "passive")
		)
		(pad "2" smd roundrect
			(at 0.48 0 270)
			(size 0.59 0.64)
			(layers "F.Cu" "F.Mask" "F.Paste")
			(roundrect_rratio 0.25)
			(net 266 "Net-(Q1-D)")
			(pintype "passive")
		)
	)
	(footprint "antmicro-footprints:C_0603_1608Metric"
		(layer "F.Cu")
		(at 152.91 188.535 180)
		(descr "Capacitor SMD 0603")
		(tags "capacitor 0603")
		(property "Reference" "C180"
			(at -4.04 -0.365 0)
			(layer "F.SilkS")
			(effects
				(font
					(size 0.7 0.7)
					(thickness 0.15)
				)
				(justify right bottom)
			)
		)
		(property "Value" "C_1u_25V_0603"
			(at -1.42757 1.770288 0)
			(layer "F.Fab")
			(effects
				(font
					(size 0.7 0.7)
					(thickness 0.15)
				)
				(justify right bottom)
			)
		)
		(property "Datasheet" "https://product.samsungsem.com/mlcc/CL10A105KA8NNN.do"
			(at 0 0 180)
			(layer "F.Fab")
			(hide yes)
			(effects
				(font
					(size 1.27 1.27)
					(thickness 0.15)
				)
			)
		)
		(property "Manufacturer" "Samsung Electro-Mechanics"
			(at 0 0 180)
			(unlocked yes)
			(layer "F.Fab")
			(hide yes)
			(effects
				(font
					(size 1 1)
					(thickness 0.15)
				)
			)
		)
		(property "MPN" "CL10A105KA8NNNC"
			(at 0 0 180)
			(unlocked yes)
			(layer "F.Fab")
			(hide yes)
			(effects
				(font
					(size 1 1)
					(thickness 0.15)
				)
			)
		)
		(property "Val" "1u"
			(at 0 0 180)
			(unlocked yes)
			(layer "F.Fab")
			(hide yes)
			(effects
				(font
					(size 1 1)
					(thickness 0.15)
				)
			)
		)
		(property "License" "Apache-2.0"
			(at 0 0 180)
			(unlocked yes)
			(layer "F.Fab")
			(hide yes)
			(effects
				(font
					(size 1 1)
					(thickness 0.15)
				)
			)
		)
		(property "Author" "Antmicro"
			(at 0 0 180)
			(unlocked yes)
			(layer "F.Fab")
			(hide yes)
			(effects
				(font
					(size 1 1)
					(thickness 0.15)
				)
			)
		)
		(property "Voltage" "25V"
			(at 0 0 180)
			(unlocked yes)
			(layer "F.Fab")
			(hide yes)
			(effects
				(font
					(size 1 1)
					(thickness 0.15)
				)
			)
		)
		(property "Dielectric" ""
			(at 0 0 180)
			(unlocked yes)
			(layer "F.Fab")
			(hide yes)
			(effects
				(font
					(size 1 1)
					(thickness 0.15)
				)
			)
		)
		(sheetname "/Supply/")
		(sheetfile "supply.kicad_sch")
		(attr smd)
		(fp_line
			(start -0.15 0.4)
			(end 0.15 0.4)
			(stroke
				(width 0.15)
				(type solid)
			)
			(layer "F.SilkS")
		)
		(fp_line
			(start -0.15 -0.4)
			(end 0.15 -0.4)
			(stroke
				(width 0.15)
				(type solid)
			)
			(layer "F.SilkS")
		)
		(fp_rect
			(start -1.25 -0.65)
			(end 1.25 0.65)
			(stroke
				(width 0.05)
				(type solid)
			)
			(fill no)
			(layer "F.CrtYd")
		)
		(fp_rect
			(start -0.8 -0.4)
			(end 0.8 0.4)
			(stroke
				(width 0.15)
				(type solid)
			)
			(fill no)
			(layer "F.Fab")
		)
		(fp_text user "License: Apache-2.0"
			(at -1.682 5.895 180)
			(layer "F.Fab")
			(effects
				(font
					(size 0.7 0.7)
					(thickness 0.15)
				)
				(justify left bottom)
			)
		)
		(fp_text user "${REFERENCE}"
			(at -1.682 3.895 180)
			(layer "F.Fab")
			(effects
				(font
					(size 0.7 0.7)
					(thickness 0.15)
				)
				(justify left bottom)
			)
		)
		(fp_text user "Author: Antmicro"
			(at -1.682 4.894 180)
			(layer "F.Fab")
			(effects
				(font
					(size 0.7 0.7)
					(thickness 0.15)
				)
				(justify left bottom)
			)
		)
		(pad "1" smd roundrect
			(at -0.7 0 180)
			(size 0.8 1)
			(layers "F.Cu" "F.Mask" "F.Paste")
			(roundrect_rratio 0.2)
			(net 1 "GND")
			(pintype "passive")
		)
		(pad "2" smd roundrect
			(at 0.7 0 180)
			(size 0.8 1)
			(layers "F.Cu" "F.Mask" "F.Paste")
			(roundrect_rratio 0.2)
			(net 35 "VDC")
			(pintype "passive")
		)
	)
	(footprint "antmicro-footprints:TP_SMD_1mm"
		(layer "F.Cu")
		(at 244.125 147.65)
		(property "Reference" "TP9"
			(at 0 -0.731898 0)
			(layer "F.SilkS")
			(hide yes)
			(effects
				(font
					(size 0.7 0.7)
					(thickness 0.15)
				)
				(justify left bottom)
			)
		)
		(property "Value" "TP_1mm_SMD"
			(at 0 1.4 0)
			(layer "F.Fab")
			(effects
				(font
					(size 0.7 0.7)
					(thickness 0.15)
				)
				(justify left bottom)
			)
		)
		(property "MPN" ""
			(at 0 0 0)
			(unlocked yes)
			(layer "F.Fab")
			(hide yes)
			(effects
				(font
					(size 1 1)
					(thickness 0.15)
				)
			)
		)
		(property "Manufacturer" ""
			(at 0 0 0)
			(unlocked yes)
			(layer "F.Fab")
			(hide yes)
			(effects
				(font
					(size 1 1)
					(thickness 0.15)
				)
			)
		)
		(property "Author" "Antmicro"
			(at 0 0 0)
			(unlocked yes)
			(layer "F.Fab")
			(hide yes)
			(effects
				(font
					(size 1 1)
					(thickness 0.15)
				)
			)
		)
		(property "License" "Apache-2.0"
			(at 0 0 0)
			(unlocked yes)
			(layer "F.Fab")
			(hide yes)
			(effects
				(font
					(size 1 1)
					(thickness 0.15)
				)
			)
		)
		(sheetname "/Supply/DC-DC IO/")
		(sheetfile "dc-dc-io.kicad_sch")
		(attr exclude_from_pos_files)
		(fp_circle
			(center 0 0)
			(end 0.6 0)
			(stroke
				(width 0.05)
				(type default)
			)
			(fill no)
			(layer "F.CrtYd")
		)
		(fp_text user "${REFERENCE}"
			(at -0.5 2.8 0)
			(layer "F.Fab")
			(effects
				(font
					(size 0.7 0.7)
					(thickness 0.15)
				)
				(justify left bottom)
			)
		)
		(fp_text user "Author: Antmicro"
			(at -0.5 4 0)
			(layer "F.Fab")
			(effects
				(font
					(size 0.7 0.7)
					(thickness 0.15)
				)
				(justify left bottom)
			)
		)
		(fp_text user "License: Apache-2.0"
			(at -0.5 5.2 0)
			(layer "F.Fab")
			(effects
				(font
					(size 0.7 0.7)
					(thickness 0.15)
				)
				(justify left bottom)
			)
		)
		(pad "1" smd circle
			(at 0 0)
			(size 1 1)
			(layers "F.Cu" "F.Mask")
			(net 687 "VDDQ")
			(pinfunction "1")
			(pintype "passive")
		)
	)
	(footprint "antmicro-footprints:R_0402_1005Metric"
		(layer "F.Cu")
		(at 146.174499 173.234 90)
		(descr "Resistor SMD 0402")
		(tags "resistor SMD 0402")
		(property "Reference" "R93"
			(at -3.116 0.485501 90)
			(layer "F.SilkS")
			(effects
				(font
					(size 0.7 0.7)
					(thickness 0.15)
				)
				(justify left bottom)
			)
		)
		(property "Value" "R_0R_0402"
			(at -1.011843 1.772047 90)
			(layer "F.Fab")
			(effects
				(font
					(size 0.7 0.7)
					(thickness 0.15)
				)
				(justify left bottom)
			)
		)
		(property "Datasheet" "https://industrial.panasonic.com/cdbs/www-data/pdf/RDA0000/AOA0000C301.pdf"
			(at 0 0 90)
			(layer "F.Fab")
			(hide yes)
			(effects
				(font
					(size 1.27 1.27)
					(thickness 0.15)
				)
			)
		)
		(property "Manufacturer" "Panasonic"
			(at 0 0 90)
			(unlocked yes)
			(layer "F.Fab")
			(hide yes)
			(effects
				(font
					(size 1 1)
					(thickness 0.15)
				)
			)
		)
		(property "MPN" "ERJ2GE0R00X"
			(at 0 0 90)
			(unlocked yes)
			(layer "F.Fab")
			(hide yes)
			(effects
				(font
					(size 1 1)
					(thickness 0.15)
				)
			)
		)
		(property "Val" "0R"
			(at 0 0 90)
			(unlocked yes)
			(layer "F.Fab")
			(hide yes)
			(effects
				(font
					(size 1 1)
					(thickness 0.15)
				)
			)
		)
		(property "License" "Apache-2.0"
			(at 0 0 90)
			(unlocked yes)
			(layer "F.Fab")
			(hide yes)
			(effects
				(font
					(size 1 1)
					(thickness 0.15)
				)
			)
		)
		(property "Author" "Antmicro"
			(at 0 0 90)
			(unlocked yes)
			(layer "F.Fab")
			(hide yes)
			(effects
				(font
					(size 1 1)
					(thickness 0.15)
				)
			)
		)
		(property "Tolerance" "~"
			(at 0 0 90)
			(unlocked yes)
			(layer "F.Fab")
			(hide yes)
			(effects
				(font
					(size 1 1)
					(thickness 0.15)
				)
			)
		)
		(property "Current" "1A"
			(at 0 0 90)
			(unlocked yes)
			(layer "F.Fab")
			(hide yes)
			(effects
				(font
					(size 1 1)
					(thickness 0.15)
				)
			)
		)
		(sheetname "/Debug FTDI + VNA/")
		(sheetfile "debug-ftdi.kicad_sch")
		(attr smd)
		(fp_rect
			(start -0.925 -0.47)
			(end 0.925 0.47)
			(stroke
				(width 0.05)
				(type default)
			)
			(fill no)
			(layer "F.CrtYd")
		)
		(fp_rect
			(start -0.5 -0.25)
			(end 0.5 0.25)
			(stroke
				(width 0.15)
				(type solid)
			)
			(fill no)
			(layer "F.Fab")
		)
		(fp_text user "Author: Antmicro"
			(at -0.95 4.169 90)
			(layer "F.Fab")
			(effects
				(font
					(size 0.7 0.7)
					(thickness 0.15)
				)
				(justify left bottom)
			)
		)
		(fp_text user "${REFERENCE}"
			(at -0.95 3.168 90)
			(layer "F.Fab")
			(effects
				(font
					(size 0.7 0.7)
					(thickness 0.15)
				)
				(justify left bottom)
			)
		)
		(fp_text user "License: Apache-2.0"
			(at -0.95 5.169 90)
			(layer "F.Fab")
			(effects
				(font
					(size 0.7 0.7)
					(thickness 0.15)
				)
				(justify left bottom)
			)
		)
		(pad "1" smd roundrect
			(at -0.48 0 90)
			(size 0.59 0.64)
			(layers "F.Cu" "F.Mask" "F.Paste")
			(roundrect_rratio 0.25)
			(net 527 "/Debug FTDI + VNA/FTDI.SDA")
			(pintype "passive")
		)
		(pad "2" smd roundrect
			(at 0.48 0 90)
			(size 0.59 0.64)
			(layers "F.Cu" "F.Mask" "F.Paste")
			(roundrect_rratio 0.25)
			(net 139 "/Debug FTDI + VNA/FTDI_SDA_IN")
			(pintype "passive")
		)
	)
)
